# T6G (Grand Teton) — schematic netlist excerpt (pin names and nets, part order shuffled) for the footprints in the layout excerpt that follows; sources: Cadence DE-HDL packaged netlist, KiCad conversion of 04192023_DAF0TMB3IC0_F0TG_MB_C_brd_V02_OCP.brd

R479  Q_RES  10K 1% CHIP  pkg 0402LF  page 188 : A = P5V ; B = PWRGD_P5V_R
C854  Q_CAP_DIFFBUS  DIFF BUS_0.22UF 6.3V 20% X6S  pkg C0201  page 64 : \1\ = P5E_CPU0_P2_TX_C_DN<7> ; \2\ = P5E_CPU0_P2_TX_DN<7>
C2149  Q_CAP  22UF 4V 20% X6S  pkg C0402  page 68 : A = PVDDIO_P0 ; B = GND

(kicad_pcb
	(version 20260206)
	(generator "pcbnew")
	(generator_version "10.0")
	(general
		(thickness 1.6)
		(legacy_teardrops no)
	)
	(paper "A4")
	(title_block
		(title "04192023_DAF0TMB3IC0_F0TG_MB_C_brd_V02_OCP.brd")
		(comment 1 "Grand Teton / footprints 3948-3950 of 8354")
	)
	(layers
		(0 "F.Cu" signal "TOP")
		(4 "In1.Cu" signal "GND")
		(6 "In2.Cu" signal "IN1")
		(8 "In3.Cu" signal "GND1")
		(10 "In4.Cu" signal "IN2")
		(12 "In5.Cu" signal "GND2")
		(14 "In6.Cu" signal "IN3")
		(16 "In7.Cu" signal "GND3")
		(18 "In8.Cu" signal "VCC")
		(20 "In9.Cu" signal "VCC1")
		(22 "In10.Cu" signal "GND4")
		(24 "In11.Cu" signal "IN4")
		(26 "In12.Cu" signal "GND5")
		(28 "In13.Cu" signal "IN5")
		(30 "In14.Cu" signal "GND6")
		(32 "In15.Cu" signal "IN6")
		(34 "In16.Cu" signal "GND7")
		(2 "B.Cu" signal "BOTTOM")
		(9 "F.Adhes" user "F.Adhesive")
		(11 "B.Adhes" user "B.Adhesive")
		(13 "F.Paste" user "Package Geometry/Pastemask Top")
		(15 "B.Paste" user "Package Geometry/Pastemask Bottom")
		(5 "F.SilkS" user "Ref Des/Silkscreen Top")
		(7 "B.SilkS" user "Ref Des/Silkscreen Bottom")
		(1 "F.Mask" user "Board Geometry/Soldermask Top")
		(3 "B.Mask" user "Board Geometry/Soldermask Bottom")
		(17 "Dwgs.User" user "User.Drawings")
		(19 "Cmts.User" user "User.Comments")
		(21 "Eco1.User" user "User.Eco1")
		(23 "Eco2.User" user "User.Eco2")
		(25 "Edge.Cuts" user "Board Geometry/Outline")
		(27 "Margin" user)
		(31 "F.CrtYd" user "Package Geometry/Place Bound Top")
		(29 "B.CrtYd" user "Package Geometry/Place Bound Bottom")
		(35 "F.Fab" user "Ref Des/Assembly Top")
		(33 "B.Fab" user "Ref Des/Assembly Bottom")
	)
	(footprint ""
		(layer "F.Cu")
		(at 169.418 -135.509 180)
		(property "Reference" "R479"
			(at 0 0 180)
			(layer "F.SilkS")
			(hide yes)
			(effects
				(font
					(size 1.27 1.27)
				)
			)
		)
		(property "Value" ""
			(at 0 0 180)
			(layer "F.Fab")
			(effects
				(font
					(size 1.27 1.27)
				)
			)
		)
		(duplicate_pad_numbers_are_jumpers no)
		(fp_line
			(start 0.7874 0.4064)
			(end -0.7874 0.4064)
			(stroke
				(width 0.1524)
				(type default)
			)
			(layer "F.SilkS")
		)
		(fp_line
			(start 0.7874 -0.4064)
			(end 0.7874 0.4064)
			(stroke
				(width 0.1524)
				(type default)
			)
			(layer "F.SilkS")
		)
		(fp_line
			(start -0.7874 0.4064)
			(end -0.7874 -0.4064)
			(stroke
				(width 0.1524)
				(type default)
			)
			(layer "F.SilkS")
		)
		(fp_line
			(start -0.7874 -0.4064)
			(end 0.7874 -0.4064)
			(stroke
				(width 0.1524)
				(type default)
			)
			(layer "F.SilkS")
		)
		(fp_line
			(start 0.67945 0.3048)
			(end 0.120396 0.3048)
			(stroke
				(width 0.1)
				(type default)
			)
			(layer "F.Fab")
		)
		(fp_line
			(start 0.67945 -0.3048)
			(end 0.67945 0.3048)
			(stroke
				(width 0.1)
				(type default)
			)
			(layer "F.Fab")
		)
		(fp_line
			(start 0.12065 -0.2794)
			(end 0.12065 -0.3048)
			(stroke
				(width 0.1)
				(type default)
			)
			(layer "F.Fab")
		)
		(fp_line
			(start 0.12065 -0.3048)
			(end 0.67945 -0.3048)
			(stroke
				(width 0.1)
				(type default)
			)
			(layer "F.Fab")
		)
		(fp_line
			(start 0.120396 0.3048)
			(end 0.120396 0.2794)
			(stroke
				(width 0.1)
				(type default)
			)
			(layer "F.Fab")
		)
		(fp_line
			(start 0.120396 0.2794)
			(end -0.12065 0.2794)
			(stroke
				(width 0.1)
				(type default)
			)
			(layer "F.Fab")
		)
		(fp_line
			(start -0.12065 0.3048)
			(end -0.67945 0.3048)
			(stroke
				(width 0.1)
				(type default)
			)
			(layer "F.Fab")
		)
		(fp_line
			(start -0.12065 0.2794)
			(end -0.12065 0.3048)
			(stroke
				(width 0.1)
				(type default)
			)
			(layer "F.Fab")
		)
		(fp_line
			(start -0.12065 -0.2794)
			(end 0.12065 -0.2794)
			(stroke
				(width 0.1)
				(type default)
			)
			(layer "F.Fab")
		)
		(fp_line
			(start -0.12065 -0.305054)
			(end -0.12065 -0.2794)
			(stroke
				(width 0.1)
				(type default)
			)
			(layer "F.Fab")
		)
		(fp_line
			(start -0.67945 0.3048)
			(end -0.67945 -0.305054)
			(stroke
				(width 0.1)
				(type default)
			)
			(layer "F.Fab")
		)
		(fp_line
			(start -0.67945 -0.305054)
			(end -0.12065 -0.305054)
			(stroke
				(width 0.1)
				(type default)
			)
			(layer "F.Fab")
		)
		(pad "1" smd circle
			(at -0.40005 0 180)
			(size 0 0)
			(layers "F.Cu" "F.Mask" "F.Paste")
			(net "P5V")
		)
		(pad "2" smd circle
			(at 0.40005 0 180)
			(size 0 0)
			(layers "F.Cu" "F.Mask" "F.Paste")
			(net "PWRGD_P5V_R")
		)
	)
	(footprint ""
		(layer "F.Cu")
		(at 411.44444 -383.88163 -90)
		(property "Reference" "C854"
			(at 0 0 270)
			(layer "F.SilkS")
			(hide yes)
			(effects
				(font
					(size 1.27 1.27)
				)
			)
		)
		(property "Value" ""
			(at 0 0 270)
			(layer "F.Fab")
			(effects
				(font
					(size 1.27 1.27)
				)
			)
		)
		(duplicate_pad_numbers_are_jumpers no)
		(fp_line
			(start -0.299974 0.150114)
			(end -0.299974 -0.150114)
			(stroke
				(width 0.1)
				(type default)
			)
			(layer "F.Fab")
		)
		(fp_line
			(start 0.299974 0.150114)
			(end -0.299974 0.150114)
			(stroke
				(width 0.1)
				(type default)
			)
			(layer "F.Fab")
		)
		(fp_line
			(start -0.299974 -0.150114)
			(end 0.299974 -0.150114)
			(stroke
				(width 0.1)
				(type default)
			)
			(layer "F.Fab")
		)
		(fp_line
			(start 0.299974 -0.150114)
			(end 0.299974 0.150114)
			(stroke
				(width 0.1)
				(type default)
			)
			(layer "F.Fab")
		)
		(pad "1" smd rect
			(at -0.2667 0 270)
			(size 0.3048 0.381)
			(layers "F.Cu" "F.Mask" "F.Paste")
			(net "P5E_CPU0_P2_TX_C_DN<7>")
		)
		(pad "2" smd rect
			(at 0.2667 0 270)
			(size 0.3048 0.381)
			(layers "F.Cu" "F.Mask" "F.Paste")
			(net "P5E_CPU0_P2_TX_DN<7>")
		)
	)
	(footprint ""
		(layer "F.Cu")
		(at 353.900232 -261.255002)
		(property "Reference" "C2149"
			(at 0 0 0)
			(layer "F.SilkS")
			(hide yes)
			(effects
				(font
					(size 1.27 1.27)
				)
			)
		)
		(property "Value" ""
			(at 0 0 0)
			(layer "F.Fab")
			(effects
				(font
					(size 1.27 1.27)
				)
			)
		)
		(duplicate_pad_numbers_are_jumpers no)
		(fp_line
			(start -0.7874 -0.4064)
			(end 0.7874 -0.4064)
			(stroke
				(width 0.1524)
				(type default)
			)
			(layer "F.SilkS")
		)
		(fp_line
			(start -0.7874 0.4064)
			(end -0.7874 -0.4064)
			(stroke
				(width 0.1524)
				(type default)
			)
			(layer "F.SilkS")
		)
		(fp_line
			(start 0.7874 -0.4064)
			(end 0.7874 0.4064)
			(stroke
				(width 0.1524)
				(type default)
			)
			(layer "F.SilkS")
		)
		(fp_line
			(start 0.7874 0.4064)
			(end -0.7874 0.4064)
			(stroke
				(width 0.1524)
				(type default)
			)
			(layer "F.SilkS")
		)
		(fp_line
			(start -0.67945 -0.305054)
			(end -0.12065 -0.305054)
			(stroke
				(width 0.1)
				(type default)
			)
			(layer "F.Fab")
		)
		(fp_line
			(start -0.67945 0.3048)
			(end -0.67945 -0.305054)
			(stroke
				(width 0.1)
				(type default)
			)
			(layer "F.Fab")
		)
		(fp_line
			(start -0.12065 -0.305054)
			(end -0.12065 -0.2794)
			(stroke
				(width 0.1)
				(type default)
			)
			(layer "F.Fab")
		)
		(fp_line
			(start -0.12065 -0.2794)
			(end 0.12065 -0.2794)
			(stroke
				(width 0.1)
				(type default)
			)
			(layer "F.Fab")
		)
		(fp_line
			(start -0.12065 0.2794)
			(end -0.12065 0.3048)
			(stroke
				(width 0.1)
				(type default)
			)
			(layer "F.Fab")
		)
		(fp_line
			(start -0.12065 0.3048)
			(end -0.67945 0.3048)
			(stroke
				(width 0.1)
				(type default)
			)
			(layer "F.Fab")
		)
		(fp_line
			(start 0.120396 0.2794)
			(end -0.12065 0.2794)
			(stroke
				(width 0.1)
				(type default)
			)
			(layer "F.Fab")
		)
		(fp_line
			(start 0.120396 0.3048)
			(end 0.120396 0.2794)
			(stroke
				(width 0.1)
				(type default)
			)
			(layer "F.Fab")
		)
		(fp_line
			(start 0.12065 -0.3048)
			(end 0.67945 -0.3048)
			(stroke
				(width 0.1)
				(type default)
			)
			(layer "F.Fab")
		)
		(fp_line
			(start 0.12065 -0.2794)
			(end 0.12065 -0.3048)
			(stroke
				(width 0.1)
				(type default)
			)
			(layer "F.Fab")
		)
		(fp_line
			(start 0.67945 -0.3048)
			(end 0.67945 0.3048)
			(stroke
				(width 0.1)
				(type default)
			)
			(layer "F.Fab")
		)
		(fp_line
			(start 0.67945 0.3048)
			(end 0.120396 0.3048)
			(stroke
				(width 0.1)
				(type default)
			)
			(layer "F.Fab")
		)
		(pad "1" smd circle
			(at -0.40005 0)
			(size 0 0)
			(layers "F.Cu" "F.Mask" "F.Paste")
			(net "PVDDIO_P0")
		)
		(pad "2" smd circle
			(at 0.40005 0)
			(size 0 0)
			(layers "F.Cu" "F.Mask" "F.Paste")
			(net "GND")
		)
	)
)
